(kicad_pcb
	(version 20260206)
	(generator "pcbnew")
	(generator_version "10.0")
	(general
		(thickness 1.6)
		(legacy_teardrops no)
	)
	(paper "A4")
	(title_block
		(title "12092022_DA0F0TFB6D0_F0T_FAN_BOARD_MP5048_D_brd_v02_OCP.brd")
		(comment 1 "Grand Teton / footprints 280-285 of 924")
	)
	(layers
		(0 "F.Cu" signal "TOP")
		(4 "In1.Cu" signal "GND")
		(6 "In2.Cu" signal "IN1")
		(8 "In3.Cu" signal "IN2")
		(10 "In4.Cu" signal "GND1")
		(2 "B.Cu" signal "BOTTOM")
		(9 "F.Adhes" user "F.Adhesive")
		(11 "B.Adhes" user "B.Adhesive")
		(13 "F.Paste" user "Package Geometry/Pastemask Top")
		(15 "B.Paste" user "Package Geometry/Pastemask Bottom")
		(5 "F.SilkS" user "Ref Des/Silkscreen Top")
		(7 "B.SilkS" user "Ref Des/Silkscreen Bottom")
		(1 "F.Mask" user "Board Geometry/Soldermask Top")
		(3 "B.Mask" user "Board Geometry/Soldermask Bottom")
		(17 "Dwgs.User" user "User.Drawings")
		(19 "Cmts.User" user "User.Comments")
		(21 "Eco1.User" user "User.Eco1")
		(23 "Eco2.User" user "User.Eco2")
		(25 "Edge.Cuts" user "Board Geometry/Outline")
		(27 "Margin" user)
		(31 "F.CrtYd" user "Package Geometry/Place Bound Top")
		(29 "B.CrtYd" user "Package Geometry/Place Bound Bottom")
		(35 "F.Fab" user "Ref Des/Assembly Top")
		(33 "B.Fab" user "Ref Des/Assembly Bottom")
	)
	(footprint ""
		(layer "F.Cu")
		(at 30.353 -191.008 180)
		(property "Reference" "R4959"
			(at 0 0 180)
			(layer "F.SilkS")
			(hide yes)
			(effects
				(font
					(size 1.27 1.27)
				)
			)
		)
		(property "Value" ""
			(at 0 0 180)
			(layer "F.Fab")
			(effects
				(font
					(size 1.27 1.27)
				)
			)
		)
		(duplicate_pad_numbers_are_jumpers no)
		(fp_line
			(start 0.7874 0.4064)
			(end -0.7874 0.4064)
			(stroke
				(width 0.1524)
				(type default)
			)
			(layer "F.SilkS")
		)
		(fp_line
			(start 0.7874 -0.4064)
			(end 0.7874 0.4064)
			(stroke
				(width 0.1524)
				(type default)
			)
			(layer "F.SilkS")
		)
		(fp_line
			(start -0.7874 0.4064)
			(end -0.7874 -0.4064)
			(stroke
				(width 0.1524)
				(type default)
			)
			(layer "F.SilkS")
		)
		(fp_line
			(start -0.7874 -0.4064)
			(end 0.7874 -0.4064)
			(stroke
				(width 0.1524)
				(type default)
			)
			(layer "F.SilkS")
		)
		(fp_line
			(start 0.67945 0.3048)
			(end 0.120396 0.3048)
			(stroke
				(width 0.1)
				(type default)
			)
			(layer "F.Fab")
		)
		(fp_line
			(start 0.67945 -0.3048)
			(end 0.67945 0.3048)
			(stroke
				(width 0.1)
				(type default)
			)
			(layer "F.Fab")
		)
		(fp_line
			(start 0.12065 -0.2794)
			(end 0.12065 -0.3048)
			(stroke
				(width 0.1)
				(type default)
			)
			(layer "F.Fab")
		)
		(fp_line
			(start 0.12065 -0.3048)
			(end 0.67945 -0.3048)
			(stroke
				(width 0.1)
				(type default)
			)
			(layer "F.Fab")
		)
		(fp_line
			(start 0.120396 0.3048)
			(end 0.120396 0.2794)
			(stroke
				(width 0.1)
				(type default)
			)
			(layer "F.Fab")
		)
		(fp_line
			(start 0.120396 0.2794)
			(end -0.12065 0.2794)
			(stroke
				(width 0.1)
				(type default)
			)
			(layer "F.Fab")
		)
		(fp_line
			(start -0.12065 0.3048)
			(end -0.67945 0.3048)
			(stroke
				(width 0.1)
				(type default)
			)
			(layer "F.Fab")
		)
		(fp_line
			(start -0.12065 0.2794)
			(end -0.12065 0.3048)
			(stroke
				(width 0.1)
				(type default)
			)
			(layer "F.Fab")
		)
		(fp_line
			(start -0.12065 -0.2794)
			(end 0.12065 -0.2794)
			(stroke
				(width 0.1)
				(type default)
			)
			(layer "F.Fab")
		)
		(fp_line
			(start -0.12065 -0.305054)
			(end -0.12065 -0.2794)
			(stroke
				(width 0.1)
				(type default)
			)
			(layer "F.Fab")
		)
		(fp_line
			(start -0.67945 0.3048)
			(end -0.67945 -0.305054)
			(stroke
				(width 0.1)
				(type default)
			)
			(layer "F.Fab")
		)
		(fp_line
			(start -0.67945 -0.305054)
			(end -0.12065 -0.305054)
			(stroke
				(width 0.1)
				(type default)
			)
			(layer "F.Fab")
		)
		(pad "1" smd circle
			(at -0.40005 0 180)
			(size 0 0)
			(layers "F.Cu" "F.Mask" "F.Paste")
			(net "P52V_FAN_BUFF_EN_R")
		)
		(pad "2" smd circle
			(at 0.40005 0 180)
			(size 0 0)
			(layers "F.Cu" "F.Mask" "F.Paste")
			(net "P52V_FAN_EN")
		)
	)
	(footprint ""
		(layer "F.Cu")
		(at 50.165 -221.234 -90)
		(property "Reference" "C2025"
			(at 0 0 270)
			(layer "F.SilkS")
			(hide yes)
			(effects
				(font
					(size 1.27 1.27)
				)
			)
		)
		(property "Value" ""
			(at 0 0 270)
			(layer "F.Fab")
			(effects
				(font
					(size 1.27 1.27)
				)
			)
		)
		(duplicate_pad_numbers_are_jumpers no)
		(fp_line
			(start -0.7874 0.4064)
			(end -0.7874 -0.4064)
			(stroke
				(width 0.1524)
				(type default)
			)
			(layer "F.SilkS")
		)
		(fp_line
			(start 0.7874 0.4064)
			(end -0.7874 0.4064)
			(stroke
				(width 0.1524)
				(type default)
			)
			(layer "F.SilkS")
		)
		(fp_line
			(start -0.7874 -0.4064)
			(end 0.7874 -0.4064)
			(stroke
				(width 0.1524)
				(type default)
			)
			(layer "F.SilkS")
		)
		(fp_line
			(start 0.7874 -0.4064)
			(end 0.7874 0.4064)
			(stroke
				(width 0.1524)
				(type default)
			)
			(layer "F.SilkS")
		)
		(fp_line
			(start -0.6858 0.3048)
			(end -0.6858 -0.3048)
			(stroke
				(width 0.1)
				(type default)
			)
			(layer "F.Fab")
		)
		(fp_line
			(start -0.1016 0.3048)
			(end -0.6858 0.3048)
			(stroke
				(width 0.1)
				(type default)
			)
			(layer "F.Fab")
		)
		(fp_line
			(start 0.1016 0.3048)
			(end 0.1016 0.2794)
			(stroke
				(width 0.1)
				(type default)
			)
			(layer "F.Fab")
		)
		(fp_line
			(start 0.6858 0.3048)
			(end 0.1016 0.3048)
			(stroke
				(width 0.1)
				(type default)
			)
			(layer "F.Fab")
		)
		(fp_line
			(start -0.1016 0.2794)
			(end -0.1016 0.3048)
			(stroke
				(width 0.1)
				(type default)
			)
			(layer "F.Fab")
		)
		(fp_line
			(start 0.1016 0.2794)
			(end -0.1016 0.2794)
			(stroke
				(width 0.1)
				(type default)
			)
			(layer "F.Fab")
		)
		(fp_line
			(start -0.1016 -0.2794)
			(end 0.1016 -0.2794)
			(stroke
				(width 0.1)
				(type default)
			)
			(layer "F.Fab")
		)
		(fp_line
			(start 0.1016 -0.2794)
			(end 0.1016 -0.3048)
			(stroke
				(width 0.1)
				(type default)
			)
			(layer "F.Fab")
		)
		(fp_line
			(start -0.6858 -0.3048)
			(end -0.1016 -0.3048)
			(stroke
				(width 0.1)
				(type default)
			)
			(layer "F.Fab")
		)
		(fp_line
			(start -0.1016 -0.3048)
			(end -0.1016 -0.2794)
			(stroke
				(width 0.1)
				(type default)
			)
			(layer "F.Fab")
		)
		(fp_line
			(start 0.1016 -0.3048)
			(end 0.6858 -0.3048)
			(stroke
				(width 0.1)
				(type default)
			)
			(layer "F.Fab")
		)
		(fp_line
			(start 0.6858 -0.3048)
			(end 0.6858 0.3048)
			(stroke
				(width 0.1)
				(type default)
			)
			(layer "F.Fab")
		)
		(pad "1" smd rect
			(at -0.40005 0 90)
			(size 0.4572 0.508)
			(layers "F.Cu" "F.Mask" "F.Paste")
			(net "GND")
		)
		(pad "2" smd rect
			(at 0.40005 0 90)
			(size 0.4572 0.508)
			(layers "F.Cu" "F.Mask" "F.Paste")
			(net "P12V_LED_FAN1")
		)
	)
	(footprint ""
		(layer "F.Cu")
		(at 14.351 -204.47 180)
		(property "Reference" "R5374"
			(at 0 0 180)
			(layer "F.SilkS")
			(hide yes)
			(effects
				(font
					(size 1.27 1.27)
				)
			)
		)
		(property "Value" ""
			(at 0 0 180)
			(layer "F.Fab")
			(effects
				(font
					(size 1.27 1.27)
				)
			)
		)
		(duplicate_pad_numbers_are_jumpers no)
		(fp_line
			(start 0.7874 0.4064)
			(end -0.7874 0.4064)
			(stroke
				(width 0.1524)
				(type default)
			)
			(layer "F.SilkS")
		)
		(fp_line
			(start 0.7874 -0.4064)
			(end 0.7874 0.4064)
			(stroke
				(width 0.1524)
				(type default)
			)
			(layer "F.SilkS")
		)
		(fp_line
			(start -0.7874 0.4064)
			(end -0.7874 -0.4064)
			(stroke
				(width 0.1524)
				(type default)
			)
			(layer "F.SilkS")
		)
		(fp_line
			(start -0.7874 -0.4064)
			(end 0.7874 -0.4064)
			(stroke
				(width 0.1524)
				(type default)
			)
			(layer "F.SilkS")
		)
		(fp_line
			(start 0.67945 0.3048)
			(end 0.120396 0.3048)
			(stroke
				(width 0.1)
				(type default)
			)
			(layer "F.Fab")
		)
		(fp_line
			(start 0.67945 -0.3048)
			(end 0.67945 0.3048)
			(stroke
				(width 0.1)
				(type default)
			)
			(layer "F.Fab")
		)
		(fp_line
			(start 0.12065 -0.2794)
			(end 0.12065 -0.3048)
			(stroke
				(width 0.1)
				(type default)
			)
			(layer "F.Fab")
		)
		(fp_line
			(start 0.12065 -0.3048)
			(end 0.67945 -0.3048)
			(stroke
				(width 0.1)
				(type default)
			)
			(layer "F.Fab")
		)
		(fp_line
			(start 0.120396 0.3048)
			(end 0.120396 0.2794)
			(stroke
				(width 0.1)
				(type default)
			)
			(layer "F.Fab")
		)
		(fp_line
			(start 0.120396 0.2794)
			(end -0.12065 0.2794)
			(stroke
				(width 0.1)
				(type default)
			)
			(layer "F.Fab")
		)
		(fp_line
			(start -0.12065 0.3048)
			(end -0.67945 0.3048)
			(stroke
				(width 0.1)
				(type default)
			)
			(layer "F.Fab")
		)
		(fp_line
			(start -0.12065 0.2794)
			(end -0.12065 0.3048)
			(stroke
				(width 0.1)
				(type default)
			)
			(layer "F.Fab")
		)
		(fp_line
			(start -0.12065 -0.2794)
			(end 0.12065 -0.2794)
			(stroke
				(width 0.1)
				(type default)
			)
			(layer "F.Fab")
		)
		(fp_line
			(start -0.12065 -0.305054)
			(end -0.12065 -0.2794)
			(stroke
				(width 0.1)
				(type default)
			)
			(layer "F.Fab")
		)
		(fp_line
			(start -0.67945 0.3048)
			(end -0.67945 -0.305054)
			(stroke
				(width 0.1)
				(type default)
			)
			(layer "F.Fab")
		)
		(fp_line
			(start -0.67945 -0.305054)
			(end -0.12065 -0.305054)
			(stroke
				(width 0.1)
				(type default)
			)
			(layer "F.Fab")
		)
		(pad "1" smd rect
			(at -0.40005 0)
			(size 0.4572 0.508)
			(layers "F.Cu" "F.Mask" "F.Paste")
			(net "FAN_6_FAIL_LED_R_N")
		)
		(pad "2" smd rect
			(at 0.40005 0)
			(size 0.4572 0.508)
			(layers "F.Cu" "F.Mask" "F.Paste")
			(net "FAN_6_FAIL_R_LED_N")
		)
	)
	(footprint ""
		(layer "F.Cu")
		(at 42.037 -191.516)
		(property "Reference" "C1953"
			(at 0 0 0)
			(layer "F.SilkS")
			(hide yes)
			(effects
				(font
					(size 1.27 1.27)
				)
			)
		)
		(property "Value" ""
			(at 0 0 0)
			(layer "F.Fab")
			(effects
				(font
					(size 1.27 1.27)
				)
			)
		)
		(duplicate_pad_numbers_are_jumpers no)
		(fp_line
			(start -0.7874 -0.4064)
			(end 0.7874 -0.4064)
			(stroke
				(width 0.1524)
				(type default)
			)
			(layer "F.SilkS")
		)
		(fp_line
			(start -0.7874 0.4064)
			(end -0.7874 -0.4064)
			(stroke
				(width 0.1524)
				(type default)
			)
			(layer "F.SilkS")
		)
		(fp_line
			(start 0.7874 -0.4064)
			(end 0.7874 0.4064)
			(stroke
				(width 0.1524)
				(type default)
			)
			(layer "F.SilkS")
		)
		(fp_line
			(start 0.7874 0.4064)
			(end -0.7874 0.4064)
			(stroke
				(width 0.1524)
				(type default)
			)
			(layer "F.SilkS")
		)
		(fp_line
			(start -0.67945 -0.305054)
			(end -0.12065 -0.305054)
			(stroke
				(width 0.1)
				(type default)
			)
			(layer "F.Fab")
		)
		(fp_line
			(start -0.67945 0.3048)
			(end -0.67945 -0.305054)
			(stroke
				(width 0.1)
				(type default)
			)
			(layer "F.Fab")
		)
		(fp_line
			(start -0.12065 -0.305054)
			(end -0.12065 -0.2794)
			(stroke
				(width 0.1)
				(type default)
			)
			(layer "F.Fab")
		)
		(fp_line
			(start -0.12065 -0.2794)
			(end 0.12065 -0.2794)
			(stroke
				(width 0.1)
				(type default)
			)
			(layer "F.Fab")
		)
		(fp_line
			(start -0.12065 0.2794)
			(end -0.12065 0.3048)
			(stroke
				(width 0.1)
				(type default)
			)
			(layer "F.Fab")
		)
		(fp_line
			(start -0.12065 0.3048)
			(end -0.67945 0.3048)
			(stroke
				(width 0.1)
				(type default)
			)
			(layer "F.Fab")
		)
		(fp_line
			(start 0.120396 0.2794)
			(end -0.12065 0.2794)
			(stroke
				(width 0.1)
				(type default)
			)
			(layer "F.Fab")
		)
		(fp_line
			(start 0.120396 0.3048)
			(end 0.120396 0.2794)
			(stroke
				(width 0.1)
				(type default)
			)
			(layer "F.Fab")
		)
		(fp_line
			(start 0.12065 -0.3048)
			(end 0.67945 -0.3048)
			(stroke
				(width 0.1)
				(type default)
			)
			(layer "F.Fab")
		)
		(fp_line
			(start 0.12065 -0.2794)
			(end 0.12065 -0.3048)
			(stroke
				(width 0.1)
				(type default)
			)
			(layer "F.Fab")
		)
		(fp_line
			(start 0.67945 -0.3048)
			(end 0.67945 0.3048)
			(stroke
				(width 0.1)
				(type default)
			)
			(layer "F.Fab")
		)
		(fp_line
			(start 0.67945 0.3048)
			(end 0.120396 0.3048)
			(stroke
				(width 0.1)
				(type default)
			)
			(layer "F.Fab")
		)
		(pad "1" smd circle
			(at -0.40005 0)
			(size 0 0)
			(layers "F.Cu" "F.Mask" "F.Paste")
			(net "P3V3_AUX")
		)
		(pad "2" smd circle
			(at 0.40005 0)
			(size 0 0)
			(layers "F.Cu" "F.Mask" "F.Paste")
			(net "GND")
		)
	)
	(footprint ""
		(layer "F.Cu")
		(at 17.907 -167.005 180)
		(property "Reference" "R5498"
			(at 0 0 180)
			(layer "F.SilkS")
			(hide yes)
			(effects
				(font
					(size 1.27 1.27)
				)
			)
		)
		(property "Value" ""
			(at 0 0 180)
			(layer "F.Fab")
			(effects
				(font
					(size 1.27 1.27)
				)
			)
		)
		(duplicate_pad_numbers_are_jumpers no)
		(fp_line
			(start 0.7874 0.4064)
			(end -0.7874 0.4064)
			(stroke
				(width 0.1524)
				(type default)
			)
			(layer "F.SilkS")
		)
		(fp_line
			(start 0.7874 -0.4064)
			(end 0.7874 0.4064)
			(stroke
				(width 0.1524)
				(type default)
			)
			(layer "F.SilkS")
		)
		(fp_line
			(start -0.7874 0.4064)
			(end -0.7874 -0.4064)
			(stroke
				(width 0.1524)
				(type default)
			)
			(layer "F.SilkS")
		)
		(fp_line
			(start -0.7874 -0.4064)
			(end 0.7874 -0.4064)
			(stroke
				(width 0.1524)
				(type default)
			)
			(layer "F.SilkS")
		)
		(fp_line
			(start 0.67945 0.3048)
			(end 0.120396 0.3048)
			(stroke
				(width 0.1)
				(type default)
			)
			(layer "F.Fab")
		)
		(fp_line
			(start 0.67945 -0.3048)
			(end 0.67945 0.3048)
			(stroke
				(width 0.1)
				(type default)
			)
			(layer "F.Fab")
		)
		(fp_line
			(start 0.12065 -0.2794)
			(end 0.12065 -0.3048)
			(stroke
				(width 0.1)
				(type default)
			)
			(layer "F.Fab")
		)
		(fp_line
			(start 0.12065 -0.3048)
			(end 0.67945 -0.3048)
			(stroke
				(width 0.1)
				(type default)
			)
			(layer "F.Fab")
		)
		(fp_line
			(start 0.120396 0.3048)
			(end 0.120396 0.2794)
			(stroke
				(width 0.1)
				(type default)
			)
			(layer "F.Fab")
		)
		(fp_line
			(start 0.120396 0.2794)
			(end -0.12065 0.2794)
			(stroke
				(width 0.1)
				(type default)
			)
			(layer "F.Fab")
		)
		(fp_line
			(start -0.12065 0.3048)
			(end -0.67945 0.3048)
			(stroke
				(width 0.1)
				(type default)
			)
			(layer "F.Fab")
		)
		(fp_line
			(start -0.12065 0.2794)
			(end -0.12065 0.3048)
			(stroke
				(width 0.1)
				(type default)
			)
			(layer "F.Fab")
		)
		(fp_line
			(start -0.12065 -0.2794)
			(end 0.12065 -0.2794)
			(stroke
				(width 0.1)
				(type default)
			)
			(layer "F.Fab")
		)
		(fp_line
			(start -0.12065 -0.305054)
			(end -0.12065 -0.2794)
			(stroke
				(width 0.1)
				(type default)
			)
			(layer "F.Fab")
		)
		(fp_line
			(start -0.67945 0.3048)
			(end -0.67945 -0.305054)
			(stroke
				(width 0.1)
				(type default)
			)
			(layer "F.Fab")
		)
		(fp_line
			(start -0.67945 -0.305054)
			(end -0.12065 -0.305054)
			(stroke
				(width 0.1)
				(type default)
			)
			(layer "F.Fab")
		)
		(pad "1" smd circle
			(at -0.40005 0 180)
			(size 0 0)
			(layers "F.Cu" "F.Mask" "F.Paste")
			(net "FAN_3_PRESENT_R_N")
		)
		(pad "2" smd circle
			(at 0.40005 0 180)
			(size 0 0)
			(layers "F.Cu" "F.Mask" "F.Paste")
			(net "FAN_3_PRESENT_N")
		)
	)
	(footprint ""
		(layer "F.Cu")
		(at 17.907 -173.99 180)
		(property "Reference" "R5502"
			(at 0 0 180)
			(layer "F.SilkS")
			(hide yes)
			(effects
				(font
					(size 1.27 1.27)
				)
			)
		)
		(property "Value" ""
			(at 0 0 180)
			(layer "F.Fab")
			(effects
				(font
					(size 1.27 1.27)
				)
			)
		)
		(duplicate_pad_numbers_are_jumpers no)
		(fp_line
			(start 0.7874 0.4064)
			(end -0.7874 0.4064)
			(stroke
				(width 0.1524)
				(type default)
			)
			(layer "F.SilkS")
		)
		(fp_line
			(start 0.7874 -0.4064)
			(end 0.7874 0.4064)
			(stroke
				(width 0.1524)
				(type default)
			)
			(layer "F.SilkS")
		)
		(fp_line
			(start -0.7874 0.4064)
			(end -0.7874 -0.4064)
			(stroke
				(width 0.1524)
				(type default)
			)
			(layer "F.SilkS")
		)
		(fp_line
			(start -0.7874 -0.4064)
			(end 0.7874 -0.4064)
			(stroke
				(width 0.1524)
				(type default)
			)
			(layer "F.SilkS")
		)
		(fp_line
			(start 0.67945 0.3048)
			(end 0.120396 0.3048)
			(stroke
				(width 0.1)
				(type default)
			)
			(layer "F.Fab")
		)
		(fp_line
			(start 0.67945 -0.3048)
			(end 0.67945 0.3048)
			(stroke
				(width 0.1)
				(type default)
			)
			(layer "F.Fab")
		)
		(fp_line
			(start 0.12065 -0.2794)
			(end 0.12065 -0.3048)
			(stroke
				(width 0.1)
				(type default)
			)
			(layer "F.Fab")
		)
		(fp_line
			(start 0.12065 -0.3048)
			(end 0.67945 -0.3048)
			(stroke
				(width 0.1)
				(type default)
			)
			(layer "F.Fab")
		)
		(fp_line
			(start 0.120396 0.3048)
			(end 0.120396 0.2794)
			(stroke
				(width 0.1)
				(type default)
			)
			(layer "F.Fab")
		)
		(fp_line
			(start 0.120396 0.2794)
			(end -0.12065 0.2794)
			(stroke
				(width 0.1)
				(type default)
			)
			(layer "F.Fab")
		)
		(fp_line
			(start -0.12065 0.3048)
			(end -0.67945 0.3048)
			(stroke
				(width 0.1)
				(type default)
			)
			(layer "F.Fab")
		)
		(fp_line
			(start -0.12065 0.2794)
			(end -0.12065 0.3048)
			(stroke
				(width 0.1)
				(type default)
			)
			(layer "F.Fab")
		)
		(fp_line
			(start -0.12065 -0.2794)
			(end 0.12065 -0.2794)
			(stroke
				(width 0.1)
				(type default)
			)
			(layer "F.Fab")
		)
		(fp_line
			(start -0.12065 -0.305054)
			(end -0.12065 -0.2794)
			(stroke
				(width 0.1)
				(type default)
			)
			(layer "F.Fab")
		)
		(fp_line
			(start -0.67945 0.3048)
			(end -0.67945 -0.305054)
			(stroke
				(width 0.1)
				(type default)
			)
			(layer "F.Fab")
		)
		(fp_line
			(start -0.67945 -0.305054)
			(end -0.12065 -0.305054)
			(stroke
				(width 0.1)
				(type default)
			)
			(layer "F.Fab")
		)
		(pad "1" smd circle
			(at -0.40005 0 180)
			(size 0 0)
			(layers "F.Cu" "F.Mask" "F.Paste")
			(net "FAN_7_PRESENT_R_N")
		)
		(pad "2" smd circle
			(at 0.40005 0 180)
			(size 0 0)
			(layers "F.Cu" "F.Mask" "F.Paste")
			(net "FAN_7_PRESENT_N")
		)
	)
)
